(kicad_pcb
	(version 20260206)
	(generator "pcbnew")
	(generator_version "10.0")
	(general
		(thickness 1.6)
		(legacy_teardrops no)
	)
	(paper "A4")
	(title_block
		(title "01162023_DA0F0TEBIF0_F0T_Expander_BD_F_brd_V02_OCP.brd")
		(comment 1 "Grand Teton / footprints 8812-8819 of 9728")
	)
	(layers
		(0 "F.Cu" signal "TOP")
		(4 "In1.Cu" signal "GND")
		(6 "In2.Cu" signal "VCC")
		(8 "In3.Cu" signal "VCC1")
		(10 "In4.Cu" signal "GND1")
		(12 "In5.Cu" signal "IN1")
		(14 "In6.Cu" signal "GND2")
		(16 "In7.Cu" signal "IN2")
		(18 "In8.Cu" signal "GND3")
		(20 "In9.Cu" signal "IN3")
		(22 "In10.Cu" signal "GND4")
		(24 "In11.Cu" signal "IN4")
		(26 "In12.Cu" signal "GND5")
		(28 "In13.Cu" signal "IN5")
		(30 "In14.Cu" signal "GND6")
		(32 "In15.Cu" signal "IN6")
		(34 "In16.Cu" signal "GND7")
		(2 "B.Cu" signal "BOTTOM")
		(9 "F.Adhes" user "F.Adhesive")
		(11 "B.Adhes" user "B.Adhesive")
		(13 "F.Paste" user "Package Geometry/Pastemask Top")
		(15 "B.Paste" user "Package Geometry/Pastemask Bottom")
		(5 "F.SilkS" user "Ref Des/Silkscreen Top")
		(7 "B.SilkS" user "Ref Des/Silkscreen Bottom")
		(1 "F.Mask" user "Board Geometry/Soldermask Top")
		(3 "B.Mask" user "Board Geometry/Soldermask Bottom")
		(17 "Dwgs.User" user "User.Drawings")
		(19 "Cmts.User" user "User.Comments")
		(21 "Eco1.User" user "User.Eco1")
		(23 "Eco2.User" user "User.Eco2")
		(25 "Edge.Cuts" user "Board Geometry/Outline")
		(27 "Margin" user)
		(31 "F.CrtYd" user "Package Geometry/Place Bound Top")
		(29 "B.CrtYd" user "Package Geometry/Place Bound Bottom")
		(35 "F.Fab" user "Ref Des/Assembly Top")
		(33 "B.Fab" user "Ref Des/Assembly Bottom")
	)
	(footprint ""
		(layer "B.Cu")
		(at 335.298288 -325.895208 -90)
		(property "Reference" "C4310"
			(at 0 0 90)
			(layer "B.SilkS")
			(hide yes)
			(effects
				(font
					(size 1.27 1.27)
				)
				(justify mirror)
			)
		)
		(property "Value" ""
			(at 0 0 90)
			(layer "B.Fab")
			(effects
				(font
					(size 1.27 1.27)
				)
				(justify mirror)
			)
		)
		(duplicate_pad_numbers_are_jumpers no)
		(fp_line
			(start -1.2954 0.5842)
			(end 1.2954 0.5842)
			(stroke
				(width 0.1524)
				(type default)
			)
			(layer "B.SilkS")
		)
		(fp_line
			(start 1.2954 0.5842)
			(end 1.2954 -0.5842)
			(stroke
				(width 0.1524)
				(type default)
			)
			(layer "B.SilkS")
		)
		(fp_line
			(start -1.2954 -0.5842)
			(end -1.2954 0.5842)
			(stroke
				(width 0.1524)
				(type default)
			)
			(layer "B.SilkS")
		)
		(fp_line
			(start 1.2954 -0.5842)
			(end -1.2954 -0.5842)
			(stroke
				(width 0.1524)
				(type default)
			)
			(layer "B.SilkS")
		)
		(fp_line
			(start -0.8636 0.4572)
			(end 0.8636 0.4572)
			(stroke
				(width 0.1)
				(type default)
			)
			(layer "B.Fab")
		)
		(fp_line
			(start 0.8636 0.4572)
			(end 0.8636 0.4064)
			(stroke
				(width 0.1)
				(type default)
			)
			(layer "B.Fab")
		)
		(fp_line
			(start -1.1938 0.4064)
			(end -0.8636 0.4064)
			(stroke
				(width 0.1)
				(type default)
			)
			(layer "B.Fab")
		)
		(fp_line
			(start -0.8636 0.4064)
			(end -0.8636 0.4572)
			(stroke
				(width 0.1)
				(type default)
			)
			(layer "B.Fab")
		)
		(fp_line
			(start 0.8636 0.4064)
			(end 1.1938 0.4064)
			(stroke
				(width 0.1)
				(type default)
			)
			(layer "B.Fab")
		)
		(fp_line
			(start 1.1938 0.4064)
			(end 1.1938 -0.4064)
			(stroke
				(width 0.1)
				(type default)
			)
			(layer "B.Fab")
		)
		(fp_line
			(start -1.1938 -0.4064)
			(end -1.1938 0.4064)
			(stroke
				(width 0.1)
				(type default)
			)
			(layer "B.Fab")
		)
		(fp_line
			(start -0.8636 -0.4064)
			(end -1.1938 -0.4064)
			(stroke
				(width 0.1)
				(type default)
			)
			(layer "B.Fab")
		)
		(fp_line
			(start 0.8636 -0.4064)
			(end 0.8636 -0.4572)
			(stroke
				(width 0.1)
				(type default)
			)
			(layer "B.Fab")
		)
		(fp_line
			(start 1.1938 -0.4064)
			(end 0.8636 -0.4064)
			(stroke
				(width 0.1)
				(type default)
			)
			(layer "B.Fab")
		)
		(fp_line
			(start -0.8636 -0.4572)
			(end -0.8636 -0.4064)
			(stroke
				(width 0.1)
				(type default)
			)
			(layer "B.Fab")
		)
		(fp_line
			(start 0.8636 -0.4572)
			(end -0.8636 -0.4572)
			(stroke
				(width 0.1)
				(type default)
			)
			(layer "B.Fab")
		)
		(pad "1" smd rect
			(at 0.7366 0 180)
			(size 0.7112 0.8128)
			(layers "B.Cu" "B.Mask" "B.Paste")
			(net "P0V8_SERDES_VDDA_PEX2_C0")
		)
		(pad "2" smd rect
			(at -0.7366 0 180)
			(size 0.7112 0.8128)
			(layers "B.Cu" "B.Mask" "B.Paste")
			(net "GND")
		)
	)
	(footprint ""
		(layer "B.Cu")
		(at 183.82488 -286.399732 90)
		(property "Reference" "C3126"
			(at 0 0 90)
			(layer "B.SilkS")
			(hide yes)
			(effects
				(font
					(size 1.27 1.27)
				)
				(justify mirror)
			)
		)
		(property "Value" ""
			(at 0 0 90)
			(layer "B.Fab")
			(effects
				(font
					(size 1.27 1.27)
				)
				(justify mirror)
			)
		)
		(duplicate_pad_numbers_are_jumpers no)
		(fp_line
			(start 0.299974 -0.150114)
			(end -0.299974 -0.150114)
			(stroke
				(width 0.1)
				(type default)
			)
			(layer "B.Fab")
		)
		(fp_line
			(start -0.299974 -0.150114)
			(end -0.299974 0.150114)
			(stroke
				(width 0.1)
				(type default)
			)
			(layer "B.Fab")
		)
		(fp_line
			(start 0.299974 0.150114)
			(end 0.299974 -0.150114)
			(stroke
				(width 0.1)
				(type default)
			)
			(layer "B.Fab")
		)
		(fp_line
			(start -0.299974 0.150114)
			(end 0.299974 0.150114)
			(stroke
				(width 0.1)
				(type default)
			)
			(layer "B.Fab")
		)
		(pad "1" smd rect
			(at 0.2667 0 270)
			(size 0.3048 0.381)
			(layers "B.Cu" "B.Mask" "B.Paste")
			(net "P1V25_SERDES_VDDPLL_PEX1")
		)
		(pad "2" smd rect
			(at -0.2667 0 270)
			(size 0.3048 0.381)
			(layers "B.Cu" "B.Mask" "B.Paste")
			(net "GND")
		)
	)
	(footprint ""
		(layer "B.Cu")
		(at 107.573318 -349.904558 90)
		(property "Reference" "C4184"
			(at 0 0 90)
			(layer "B.SilkS")
			(hide yes)
			(effects
				(font
					(size 1.27 1.27)
				)
				(justify mirror)
			)
		)
		(property "Value" ""
			(at 0 0 90)
			(layer "B.Fab")
			(effects
				(font
					(size 1.27 1.27)
				)
				(justify mirror)
			)
		)
		(duplicate_pad_numbers_are_jumpers no)
		(fp_line
			(start 0.7874 -0.4064)
			(end -0.7874 -0.4064)
			(stroke
				(width 0.1524)
				(type default)
			)
			(layer "B.SilkS")
		)
		(fp_line
			(start -0.7874 -0.4064)
			(end -0.7874 0.4064)
			(stroke
				(width 0.1524)
				(type default)
			)
			(layer "B.SilkS")
		)
		(fp_line
			(start 0.7874 0.4064)
			(end 0.7874 -0.4064)
			(stroke
				(width 0.1524)
				(type default)
			)
			(layer "B.SilkS")
		)
		(fp_line
			(start -0.7874 0.4064)
			(end 0.7874 0.4064)
			(stroke
				(width 0.1524)
				(type default)
			)
			(layer "B.SilkS")
		)
		(fp_line
			(start 0.67945 -0.305054)
			(end 0.12065 -0.305054)
			(stroke
				(width 0.1)
				(type default)
			)
			(layer "B.Fab")
		)
		(fp_line
			(start 0.12065 -0.305054)
			(end 0.12065 -0.2794)
			(stroke
				(width 0.1)
				(type default)
			)
			(layer "B.Fab")
		)
		(fp_line
			(start -0.12065 -0.3048)
			(end -0.67945 -0.3048)
			(stroke
				(width 0.1)
				(type default)
			)
			(layer "B.Fab")
		)
		(fp_line
			(start -0.67945 -0.3048)
			(end -0.67945 0.3048)
			(stroke
				(width 0.1)
				(type default)
			)
			(layer "B.Fab")
		)
		(fp_line
			(start 0.12065 -0.2794)
			(end -0.12065 -0.2794)
			(stroke
				(width 0.1)
				(type default)
			)
			(layer "B.Fab")
		)
		(fp_line
			(start -0.12065 -0.2794)
			(end -0.12065 -0.3048)
			(stroke
				(width 0.1)
				(type default)
			)
			(layer "B.Fab")
		)
		(fp_line
			(start 0.12065 0.2794)
			(end 0.12065 0.3048)
			(stroke
				(width 0.1)
				(type default)
			)
			(layer "B.Fab")
		)
		(fp_line
			(start -0.120396 0.2794)
			(end 0.12065 0.2794)
			(stroke
				(width 0.1)
				(type default)
			)
			(layer "B.Fab")
		)
		(fp_line
			(start 0.67945 0.3048)
			(end 0.67945 -0.305054)
			(stroke
				(width 0.1)
				(type default)
			)
			(layer "B.Fab")
		)
		(fp_line
			(start 0.12065 0.3048)
			(end 0.67945 0.3048)
			(stroke
				(width 0.1)
				(type default)
			)
			(layer "B.Fab")
		)
		(fp_line
			(start -0.120396 0.3048)
			(end -0.120396 0.2794)
			(stroke
				(width 0.1)
				(type default)
			)
			(layer "B.Fab")
		)
		(fp_line
			(start -0.67945 0.3048)
			(end -0.120396 0.3048)
			(stroke
				(width 0.1)
				(type default)
			)
			(layer "B.Fab")
		)
		(pad "1" smd circle
			(at 0.40005 0 270)
			(size 0 0)
			(layers "B.Cu" "B.Mask" "B.Paste")
			(net "P3V3_CLK_BUFFER_9ZXL0451E_S3_VZX3P3A")
		)
		(pad "2" smd circle
			(at -0.40005 0 270)
			(size 0 0)
			(layers "B.Cu" "B.Mask" "B.Paste")
			(net "GND")
		)
	)
	(footprint ""
		(layer "B.Cu")
		(at 299.449744 -301.599854 -90)
		(property "Reference" "C1703"
			(at 0 0 90)
			(layer "B.SilkS")
			(hide yes)
			(effects
				(font
					(size 1.27 1.27)
				)
				(justify mirror)
			)
		)
		(property "Value" ""
			(at 0 0 90)
			(layer "B.Fab")
			(effects
				(font
					(size 1.27 1.27)
				)
				(justify mirror)
			)
		)
		(duplicate_pad_numbers_are_jumpers no)
		(fp_line
			(start -0.299974 0.150114)
			(end 0.299974 0.150114)
			(stroke
				(width 0.1)
				(type default)
			)
			(layer "B.Fab")
		)
		(fp_line
			(start 0.299974 0.150114)
			(end 0.299974 -0.150114)
			(stroke
				(width 0.1)
				(type default)
			)
			(layer "B.Fab")
		)
		(fp_line
			(start -0.299974 -0.150114)
			(end -0.299974 0.150114)
			(stroke
				(width 0.1)
				(type default)
			)
			(layer "B.Fab")
		)
		(fp_line
			(start 0.299974 -0.150114)
			(end -0.299974 -0.150114)
			(stroke
				(width 0.1)
				(type default)
			)
			(layer "B.Fab")
		)
		(pad "1" smd rect
			(at 0.2667 0 90)
			(size 0.3048 0.381)
			(layers "B.Cu" "B.Mask" "B.Paste")
			(net "P0V8_SERDES_VDDA_PEX2")
		)
		(pad "2" smd rect
			(at -0.2667 0 90)
			(size 0.3048 0.381)
			(layers "B.Cu" "B.Mask" "B.Paste")
			(net "GND")
		)
	)
	(footprint ""
		(layer "B.Cu")
		(at 106.964734 -237.306612 -90)
		(property "Reference" "PC1002"
			(at 0 0 90)
			(layer "B.SilkS")
			(hide yes)
			(effects
				(font
					(size 1.27 1.27)
				)
				(justify mirror)
			)
		)
		(property "Value" ""
			(at 0 0 90)
			(layer "B.Fab")
			(effects
				(font
					(size 1.27 1.27)
				)
				(justify mirror)
			)
		)
		(duplicate_pad_numbers_are_jumpers no)
		(fp_line
			(start -1.524 0.762)
			(end 1.524 0.762)
			(stroke
				(width 0.1524)
				(type default)
			)
			(layer "B.SilkS")
		)
		(fp_line
			(start 1.524 0.762)
			(end 1.524 -0.762)
			(stroke
				(width 0.1524)
				(type default)
			)
			(layer "B.SilkS")
		)
		(fp_line
			(start -1.524 -0.762)
			(end -1.524 0.762)
			(stroke
				(width 0.1524)
				(type default)
			)
			(layer "B.SilkS")
		)
		(fp_line
			(start 1.524 -0.762)
			(end -1.524 -0.762)
			(stroke
				(width 0.1524)
				(type default)
			)
			(layer "B.SilkS")
		)
		(fp_line
			(start -1.1049 0.724916)
			(end -1.1049 -0.724916)
			(stroke
				(width 0.1)
				(type default)
			)
			(layer "B.Fab")
		)
		(fp_line
			(start 1.1049 0.724916)
			(end -1.1049 0.724916)
			(stroke
				(width 0.1)
				(type default)
			)
			(layer "B.Fab")
		)
		(fp_line
			(start -1.1049 -0.724916)
			(end 1.1049 -0.724916)
			(stroke
				(width 0.1)
				(type default)
			)
			(layer "B.Fab")
		)
		(fp_line
			(start 1.1049 -0.724916)
			(end 1.1049 0.724916)
			(stroke
				(width 0.1)
				(type default)
			)
			(layer "B.Fab")
		)
		(pad "1" smd rect
			(at 0.889 0 270)
			(size 1.016 1.27)
			(layers "B.Cu" "B.Mask" "B.Paste")
			(net "P1V8_PEX_R")
		)
		(pad "2" smd rect
			(at -0.889 0 270)
			(size 1.016 1.27)
			(layers "B.Cu" "B.Mask" "B.Paste")
			(net "GND")
		)
	)
	(footprint ""
		(layer "B.Cu")
		(at 351.645982 -142.494)
		(property "Reference" "R4804"
			(at 0 0 0)
			(layer "B.SilkS")
			(hide yes)
			(effects
				(font
					(size 1.27 1.27)
				)
				(justify mirror)
			)
		)
		(property "Value" ""
			(at 0 0 0)
			(layer "B.Fab")
			(effects
				(font
					(size 1.27 1.27)
				)
				(justify mirror)
			)
		)
		(duplicate_pad_numbers_are_jumpers no)
		(fp_line
			(start -0.7874 -0.4064)
			(end -0.7874 0.4064)
			(stroke
				(width 0.1524)
				(type default)
			)
			(layer "B.SilkS")
		)
		(fp_line
			(start -0.7874 0.4064)
			(end 0.7874 0.4064)
			(stroke
				(width 0.1524)
				(type default)
			)
			(layer "B.SilkS")
		)
		(fp_line
			(start 0.7874 -0.4064)
			(end -0.7874 -0.4064)
			(stroke
				(width 0.1524)
				(type default)
			)
			(layer "B.SilkS")
		)
		(fp_line
			(start 0.7874 0.4064)
			(end 0.7874 -0.4064)
			(stroke
				(width 0.1524)
				(type default)
			)
			(layer "B.SilkS")
		)
		(fp_line
			(start -0.67945 -0.3048)
			(end -0.67945 0.3048)
			(stroke
				(width 0.1)
				(type default)
			)
			(layer "B.Fab")
		)
		(fp_line
			(start -0.67945 0.3048)
			(end -0.120396 0.3048)
			(stroke
				(width 0.1)
				(type default)
			)
			(layer "B.Fab")
		)
		(fp_line
			(start -0.12065 -0.3048)
			(end -0.67945 -0.3048)
			(stroke
				(width 0.1)
				(type default)
			)
			(layer "B.Fab")
		)
		(fp_line
			(start -0.12065 -0.2794)
			(end -0.12065 -0.3048)
			(stroke
				(width 0.1)
				(type default)
			)
			(layer "B.Fab")
		)
		(fp_line
			(start -0.120396 0.2794)
			(end 0.12065 0.2794)
			(stroke
				(width 0.1)
				(type default)
			)
			(layer "B.Fab")
		)
		(fp_line
			(start -0.120396 0.3048)
			(end -0.120396 0.2794)
			(stroke
				(width 0.1)
				(type default)
			)
			(layer "B.Fab")
		)
		(fp_line
			(start 0.12065 -0.305054)
			(end 0.12065 -0.2794)
			(stroke
				(width 0.1)
				(type default)
			)
			(layer "B.Fab")
		)
		(fp_line
			(start 0.12065 -0.2794)
			(end -0.12065 -0.2794)
			(stroke
				(width 0.1)
				(type default)
			)
			(layer "B.Fab")
		)
		(fp_line
			(start 0.12065 0.2794)
			(end 0.12065 0.3048)
			(stroke
				(width 0.1)
				(type default)
			)
			(layer "B.Fab")
		)
		(fp_line
			(start 0.12065 0.3048)
			(end 0.67945 0.3048)
			(stroke
				(width 0.1)
				(type default)
			)
			(layer "B.Fab")
		)
		(fp_line
			(start 0.67945 -0.305054)
			(end 0.12065 -0.305054)
			(stroke
				(width 0.1)
				(type default)
			)
			(layer "B.Fab")
		)
		(fp_line
			(start 0.67945 0.3048)
			(end 0.67945 -0.305054)
			(stroke
				(width 0.1)
				(type default)
			)
			(layer "B.Fab")
		)
		(pad "1" smd circle
			(at 0.40005 0 180)
			(size 0 0)
			(layers "B.Cu" "B.Mask" "B.Paste")
			(net "NIC7_PEX_PWR_EN_R")
		)
		(pad "2" smd circle
			(at -0.40005 0 180)
			(size 0 0)
			(layers "B.Cu" "B.Mask" "B.Paste")
			(net "GND")
		)
	)
	(footprint ""
		(layer "B.Cu")
		(at 252.0188 -351.8408 180)
		(property "Reference" "PR7163"
			(at 0 0 0)
			(layer "B.SilkS")
			(hide yes)
			(effects
				(font
					(size 1.27 1.27)
				)
				(justify mirror)
			)
		)
		(property "Value" ""
			(at 0 0 0)
			(layer "B.Fab")
			(effects
				(font
					(size 1.27 1.27)
				)
				(justify mirror)
			)
		)
		(duplicate_pad_numbers_are_jumpers no)
		(fp_line
			(start 0.7874 0.4064)
			(end 0.7874 -0.4064)
			(stroke
				(width 0.1524)
				(type default)
			)
			(layer "B.SilkS")
		)
		(fp_line
			(start 0.7874 -0.4064)
			(end -0.7874 -0.4064)
			(stroke
				(width 0.1524)
				(type default)
			)
			(layer "B.SilkS")
		)
		(fp_line
			(start -0.7874 0.4064)
			(end 0.7874 0.4064)
			(stroke
				(width 0.1524)
				(type default)
			)
			(layer "B.SilkS")
		)
		(fp_line
			(start -0.7874 -0.4064)
			(end -0.7874 0.4064)
			(stroke
				(width 0.1524)
				(type default)
			)
			(layer "B.SilkS")
		)
		(fp_line
			(start 0.67945 0.3048)
			(end 0.67945 -0.305054)
			(stroke
				(width 0.1)
				(type default)
			)
			(layer "B.Fab")
		)
		(fp_line
			(start 0.67945 -0.305054)
			(end 0.12065 -0.305054)
			(stroke
				(width 0.1)
				(type default)
			)
			(layer "B.Fab")
		)
		(fp_line
			(start 0.12065 0.3048)
			(end 0.67945 0.3048)
			(stroke
				(width 0.1)
				(type default)
			)
			(layer "B.Fab")
		)
		(fp_line
			(start 0.12065 0.2794)
			(end 0.12065 0.3048)
			(stroke
				(width 0.1)
				(type default)
			)
			(layer "B.Fab")
		)
		(fp_line
			(start 0.12065 -0.2794)
			(end -0.12065 -0.2794)
			(stroke
				(width 0.1)
				(type default)
			)
			(layer "B.Fab")
		)
		(fp_line
			(start 0.12065 -0.305054)
			(end 0.12065 -0.2794)
			(stroke
				(width 0.1)
				(type default)
			)
			(layer "B.Fab")
		)
		(fp_line
			(start -0.120396 0.3048)
			(end -0.120396 0.2794)
			(stroke
				(width 0.1)
				(type default)
			)
			(layer "B.Fab")
		)
		(fp_line
			(start -0.120396 0.2794)
			(end 0.12065 0.2794)
			(stroke
				(width 0.1)
				(type default)
			)
			(layer "B.Fab")
		)
		(fp_line
			(start -0.12065 -0.2794)
			(end -0.12065 -0.3048)
			(stroke
				(width 0.1)
				(type default)
			)
			(layer "B.Fab")
		)
		(fp_line
			(start -0.12065 -0.3048)
			(end -0.67945 -0.3048)
			(stroke
				(width 0.1)
				(type default)
			)
			(layer "B.Fab")
		)
		(fp_line
			(start -0.67945 0.3048)
			(end -0.120396 0.3048)
			(stroke
				(width 0.1)
				(type default)
			)
			(layer "B.Fab")
		)
		(fp_line
			(start -0.67945 -0.3048)
			(end -0.67945 0.3048)
			(stroke
				(width 0.1)
				(type default)
			)
			(layer "B.Fab")
		)
		(pad "1" smd circle
			(at 0.40005 0)
			(size 0 0)
			(layers "B.Cu" "B.Mask" "B.Paste")
			(net "MB0_P12V_STBY_PWRGD")
		)
		(pad "2" smd circle
			(at -0.40005 0)
			(size 0 0)
			(layers "B.Cu" "B.Mask" "B.Paste")
			(net "PWRGD_P12V_AUX_R")
		)
	)
	(footprint ""
		(layer "B.Cu")
		(at 45.864272 -146.148552 180)
		(property "Reference" "C851"
			(at 0 0 0)
			(layer "B.SilkS")
			(hide yes)
			(effects
				(font
					(size 1.27 1.27)
				)
				(justify mirror)
			)
		)
		(property "Value" ""
			(at 0 0 0)
			(layer "B.Fab")
			(effects
				(font
					(size 1.27 1.27)
				)
				(justify mirror)
			)
		)
		(duplicate_pad_numbers_are_jumpers no)
		(fp_line
			(start 0.299974 0.150114)
			(end 0.299974 -0.150114)
			(stroke
				(width 0.1)
				(type default)
			)
			(layer "B.Fab")
		)
		(fp_line
			(start 0.299974 -0.150114)
			(end -0.299974 -0.150114)
			(stroke
				(width 0.1)
				(type default)
			)
			(layer "B.Fab")
		)
		(fp_line
			(start -0.299974 0.150114)
			(end 0.299974 0.150114)
			(stroke
				(width 0.1)
				(type default)
			)
			(layer "B.Fab")
		)
		(fp_line
			(start -0.299974 -0.150114)
			(end -0.299974 0.150114)
			(stroke
				(width 0.1)
				(type default)
			)
			(layer "B.Fab")
		)
		(pad "1" smd rect
			(at 0.2667 0)
			(size 0.3048 0.381)
			(layers "B.Cu" "B.Mask" "B.Paste")
			(net "P12V_NIC0")
		)
		(pad "2" smd rect
			(at -0.2667 0)
			(size 0.3048 0.381)
			(layers "B.Cu" "B.Mask" "B.Paste")
			(net "GND")
		)
	)
)
